(kicad_pcb
	(version 20260206)
	(generator "pcbnew")
	(generator_version "10.0")
	(general
		(thickness 1.6)
		(legacy_teardrops no)
	)
	(paper "A4")
	(title_block
		(title "Bryce Canyon_F.DPB_16315-1-OCP.brd")
		(comment 1 "Bryce Canyon / footprints 902-907 of 2223")
	)
	(layers
		(0 "F.Cu" signal "TOP")
		(4 "In1.Cu" signal "L2GND")
		(6 "In2.Cu" signal "L3")
		(8 "In3.Cu" signal "L4GND")
		(10 "In4.Cu" signal "L5")
		(12 "In5.Cu" signal "L6VCC")
		(14 "In6.Cu" signal "L7VCC")
		(16 "In7.Cu" signal "L8")
		(18 "In8.Cu" signal "L9GND")
		(20 "In9.Cu" signal "L10")
		(22 "In10.Cu" signal "L11GND")
		(2 "B.Cu" signal "BOTTOM")
		(9 "F.Adhes" user "F.Adhesive")
		(11 "B.Adhes" user "B.Adhesive")
		(13 "F.Paste" user "Package Geometry/Pastemask Top")
		(15 "B.Paste" user "Package Geometry/Pastemask Bottom")
		(5 "F.SilkS" user "Ref Des/Silkscreen Top")
		(7 "B.SilkS" user "Ref Des/Silkscreen Bottom")
		(1 "F.Mask" user "Board Geometry/Soldermask Top")
		(3 "B.Mask" user "Board Geometry/Soldermask Bottom")
		(17 "Dwgs.User" user "User.Drawings")
		(19 "Cmts.User" user "User.Comments")
		(21 "Eco1.User" user "User.Eco1")
		(23 "Eco2.User" user "User.Eco2")
		(25 "Edge.Cuts" user "Board Geometry/Outline")
		(27 "Margin" user)
		(31 "F.CrtYd" user "Package Geometry/Place Bound Top")
		(29 "B.CrtYd" user "Package Geometry/Place Bound Bottom")
		(35 "F.Fab" user "Ref Des/Assembly Top")
		(33 "B.Fab" user "Ref Des/Assembly Bottom")
	)
	(footprint ""
		(layer "F.Cu")
		(at 319.151 -292.143942 -90)
		(property "Reference" "R270"
			(at 0 0 270)
			(layer "F.SilkS")
			(hide yes)
			(effects
				(font
					(size 1.27 1.27)
				)
			)
		)
		(property "Value" "10KR2F-2-GP"
			(at 0.064008 -3.993896 270)
			(unlocked yes)
			(layer "F.Fab")
			(hide yes)
			(effects
				(font
					(size 1.016 1.016)
					(thickness 0.1524)
				)
			)
		)
		(property "Device Type" "R402H16"
			(at 0.064008 -5.517896 270)
			(unlocked yes)
			(layer "F.Fab")
			(hide yes)
			(effects
				(font
					(size 1.016 1.016)
					(thickness 0.1524)
				)
			)
		)
		(duplicate_pad_numbers_are_jumpers no)
		(fp_line
			(start -0.508 -0.9398)
			(end -0.508 0.9398)
			(stroke
				(width 0.1524)
				(type default)
			)
			(layer "F.SilkS")
		)
		(fp_line
			(start 0.508 -0.9398)
			(end -0.508 -0.9398)
			(stroke
				(width 0.1524)
				(type default)
			)
			(layer "F.SilkS")
		)
		(fp_rect
			(start -0.508 0.9398)
			(end 0.508 -0.9398)
			(stroke
				(width 0)
				(type default)
			)
			(fill no)
			(layer "F.CrtYd")
		)
		(fp_rect
			(start -0.508 0.9398)
			(end 0.508 -0.9398)
			(stroke
				(width 0)
				(type default)
			)
			(fill no)
			(layer "F.Fab")
		)
		(pad "1" smd custom
			(at 0 -0.4445 270)
			(size 0.1397 0.1397)
			(layers "F.Cu" "F.Mask" "F.Paste")
			(net "P3V3_STBY_A")
			(options
				(clearance outline)
				(anchor circle)
			)
			(primitives
				(gr_poly
					(pts
						(arc
							(start -0.1778 -0.2794)
							(mid -0.249642 -0.249642)
							(end -0.2794 -0.1778)
						)
						(arc
							(start -0.2794 0.1778)
							(mid -0.249642 0.249642)
							(end -0.1778 0.2794)
						)
						(arc
							(start 0.1778 0.2794)
							(mid 0.249642 0.249642)
							(end 0.2794 0.1778)
						)
						(arc
							(start 0.2794 -0.1778)
							(mid 0.249642 -0.249642)
							(end 0.1778 -0.2794)
						)
					)
					(width 0)
					(fill yes)
				)
			)
		)
		(pad "2" smd custom
			(at 0 0.4445 270)
			(size 0.1397 0.1397)
			(layers "F.Cu" "F.Mask" "F.Paste")
			(net "HDD_PRSNT_6")
			(options
				(clearance outline)
				(anchor circle)
			)
			(primitives
				(gr_poly
					(pts
						(arc
							(start -0.1778 -0.2794)
							(mid -0.249642 -0.249642)
							(end -0.2794 -0.1778)
						)
						(arc
							(start -0.2794 0.1778)
							(mid -0.249642 0.249642)
							(end -0.1778 0.2794)
						)
						(arc
							(start 0.1778 0.2794)
							(mid 0.249642 0.249642)
							(end 0.2794 0.1778)
						)
						(arc
							(start 0.2794 -0.1778)
							(mid 0.249642 -0.249642)
							(end 0.1778 -0.2794)
						)
					)
					(width 0)
					(fill yes)
				)
			)
		)
	)
	(footprint ""
		(layer "F.Cu")
		(at 463.5119 -47.792894 90)
		(property "Reference" "D34"
			(at 0 0 90)
			(layer "F.SilkS")
			(hide yes)
			(effects
				(font
					(size 1.27 1.27)
				)
			)
		)
		(property "Value" "RB551V30-GP"
			(at 0 -6.7818 90)
			(unlocked yes)
			(layer "F.Fab")
			(hide yes)
			(effects
				(font
					(size 1.016 1.016)
					(thickness 0.1524)
				)
			)
		)
		(property "Device Type" "SOD323AKH38"
			(at 0 -8.6868 90)
			(unlocked yes)
			(layer "F.Fab")
			(hide yes)
			(effects
				(font
					(size 1.016 1.016)
					(thickness 0.1524)
				)
			)
		)
		(duplicate_pad_numbers_are_jumpers no)
		(fp_line
			(start 0.889 -1.9304)
			(end 0.889 2.159)
			(stroke
				(width 0.1524)
				(type default)
			)
			(layer "F.SilkS")
		)
		(fp_line
			(start -0.889 -1.9304)
			(end 0.889 -1.9304)
			(stroke
				(width 0.1524)
				(type default)
			)
			(layer "F.SilkS")
		)
		(fp_line
			(start 0.762 2.0574)
			(end -0.762 2.0574)
			(stroke
				(width 0.508)
				(type default)
			)
			(layer "F.SilkS")
		)
		(fp_line
			(start 0.889 2.159)
			(end -0.889 2.159)
			(stroke
				(width 0.1524)
				(type default)
			)
			(layer "F.SilkS")
		)
		(fp_line
			(start -0.889 2.159)
			(end -0.889 -1.9304)
			(stroke
				(width 0.1524)
				(type default)
			)
			(layer "F.SilkS")
		)
		(fp_rect
			(start -1.016 2.3114)
			(end 1.016 -2.0066)
			(stroke
				(width 0)
				(type default)
			)
			(fill no)
			(layer "F.CrtYd")
		)
		(fp_poly
			(pts
				(xy -1.016 -2.0066) (xy 1.016 -2.0066) (xy 1.016 2.3114) (xy -1.016 2.3114)
			)
			(stroke
				(width 0)
				(type default)
			)
			(fill no)
			(layer "F.Fab")
		)
		(pad "A" smd rect
			(at 0 -1.143 90)
			(size 0.5588 1.016)
			(layers "F.Cu" "F.Mask" "F.Paste")
			(net "SW_HDD_R34")
		)
		(pad "K" smd rect
			(at 0 1.143 90)
			(size 0.5588 1.016)
			(layers "F.Cu" "F.Mask" "F.Paste")
			(net "SW_HDD_N34")
		)
	)
	(footprint ""
		(layer "F.Cu")
		(at 244.475 -254.889)
		(property "Reference" "U5"
			(at 0 0 0)
			(layer "F.SilkS")
			(hide yes)
			(effects
				(font
					(size 1.27 1.27)
				)
			)
		)
		(property "Value" "TCA9555PWR-GP"
			(at 0 -6.9342 0)
			(unlocked yes)
			(layer "F.Fab")
			(hide yes)
			(effects
				(font
					(size 1.016 1.016)
					(thickness 0.1524)
				)
			)
		)
		(property "Device Type" "TSOIC24H48"
			(at 0 -8.5852 0)
			(unlocked yes)
			(layer "F.Fab")
			(hide yes)
			(effects
				(font
					(size 1.016 1.016)
					(thickness 0.1524)
				)
			)
		)
		(duplicate_pad_numbers_are_jumpers no)
		(fp_line
			(start -4.2291 -1.397)
			(end 3.81 -1.397)
			(stroke
				(width 0.1524)
				(type default)
			)
			(layer "F.SilkS")
		)
		(fp_line
			(start -4.2291 -0.8001)
			(end -3.429 0)
			(stroke
				(width 0.1524)
				(type default)
			)
			(layer "F.SilkS")
		)
		(fp_line
			(start -4.2291 3.937)
			(end -4.2291 -1.397)
			(stroke
				(width 0.1524)
				(type default)
			)
			(layer "F.SilkS")
		)
		(fp_line
			(start -4.22656 3.81)
			(end -4.2291 1.397)
			(stroke
				(width 0.508)
				(type default)
			)
			(layer "F.SilkS")
		)
		(fp_line
			(start -3.429 0)
			(end -4.2291 0.8001)
			(stroke
				(width 0.1524)
				(type default)
			)
			(layer "F.SilkS")
		)
		(fp_line
			(start 3.81 -1.397)
			(end 3.81 1.397)
			(stroke
				(width 0.1524)
				(type default)
			)
			(layer "F.SilkS")
		)
		(fp_line
			(start 3.81 1.397)
			(end -4.2291 1.397)
			(stroke
				(width 0.1524)
				(type default)
			)
			(layer "F.SilkS")
		)
		(fp_poly
			(pts
				(xy -3.90652 -1.8542) (xy 3.90652 -1.8542) (xy 3.90652 1.8542) (xy -3.90652 1.8542)
			)
			(stroke
				(width 0)
				(type default)
			)
			(fill yes)
			(layer "F.SilkS")
		)
		(fp_poly
			(pts
				(xy -4.2164 3.81) (xy 4.2164 3.81) (xy 4.22656 -3.81) (xy -4.2164 -3.81)
			)
			(stroke
				(width 0)
				(type default)
			)
			(fill no)
			(layer "F.CrtYd")
		)
		(fp_poly
			(pts
				(xy -4.22656 -3.81) (xy 4.22656 -3.81) (xy 4.22656 3.81) (xy -4.22656 3.81)
			)
			(stroke
				(width 0)
				(type default)
			)
			(fill no)
			(layer "F.Fab")
		)
		(pad "1" smd rect
			(at -3.57632 2.8194)
			(size 0.3556 1.524)
			(layers "F.Cu" "F.Mask" "F.Paste")
			(net "IO_EXP5_INT_N")
		)
		(pad "2" smd rect
			(at -2.92608 2.8194)
			(size 0.3556 1.524)
			(layers "F.Cu" "F.Mask" "F.Paste")
			(net "IO_EXP5_A1")
		)
		(pad "3" smd rect
			(at -2.27584 2.8194)
			(size 0.3556 1.524)
			(layers "F.Cu" "F.Mask" "F.Paste")
			(net "IO_EXP5_A2")
		)
		(pad "4" smd rect
			(at -1.6256 2.8194)
			(size 0.3556 1.524)
			(layers "F.Cu" "F.Mask" "F.Paste")
			(net "DRIVE_A_16_INS")
		)
		(pad "5" smd rect
			(at -0.97536 2.8194)
			(size 0.3556 1.524)
			(layers "F.Cu" "F.Mask" "F.Paste")
			(net "DRIVE_A_17_INS")
		)
		(pad "6" smd rect
			(at -0.32512 2.8194)
			(size 0.3556 1.524)
			(layers "F.Cu" "F.Mask" "F.Paste")
			(net "DRIVE_A_18_INS")
		)
		(pad "7" smd rect
			(at 0.32512 2.8194)
			(size 0.3556 1.524)
			(layers "F.Cu" "F.Mask" "F.Paste")
			(net "DRIVE_A_19_INS")
		)
		(pad "8" smd rect
			(at 0.97536 2.8194)
			(size 0.3556 1.524)
			(layers "F.Cu" "F.Mask" "F.Paste")
			(net "DRIVE_A_20_INS")
		)
		(pad "9" smd rect
			(at 1.6256 2.8194)
			(size 0.3556 1.524)
			(layers "F.Cu" "F.Mask" "F.Paste")
			(net "DRIVE_A_21_INS")
		)
		(pad "10" smd rect
			(at 2.27584 2.8194)
			(size 0.3556 1.524)
			(layers "F.Cu" "F.Mask" "F.Paste")
			(net "DRIVE_A_22_INS")
		)
		(pad "11" smd rect
			(at 2.92608 2.8194)
			(size 0.3556 1.524)
			(layers "F.Cu" "F.Mask" "F.Paste")
			(net "DRIVE_A_23_INS")
		)
		(pad "12" smd rect
			(at 3.57632 2.8194)
			(size 0.3556 1.524)
			(layers "F.Cu" "F.Mask" "F.Paste")
			(net "GND")
		)
		(pad "13" smd rect
			(at 3.57632 -2.8194)
			(size 0.3556 1.524)
			(layers "F.Cu" "F.Mask" "F.Paste")
			(net "DRIVE_A_24_INS")
		)
		(pad "14" smd rect
			(at 2.92608 -2.8194)
			(size 0.3556 1.524)
			(layers "F.Cu" "F.Mask" "F.Paste")
			(net "DRIVE_A_25_INS")
		)
		(pad "15" smd rect
			(at 2.27584 -2.8194)
			(size 0.3556 1.524)
			(layers "F.Cu" "F.Mask" "F.Paste")
			(net "DRIVE_A_26_INS")
		)
		(pad "16" smd rect
			(at 1.6256 -2.8194)
			(size 0.3556 1.524)
			(layers "F.Cu" "F.Mask" "F.Paste")
			(net "DRIVE_A_27_INS")
		)
		(pad "17" smd rect
			(at 0.97536 -2.8194)
			(size 0.3556 1.524)
			(layers "F.Cu" "F.Mask" "F.Paste")
			(net "DRIVE_A_28_INS")
		)
		(pad "18" smd rect
			(at 0.32512 -2.8194)
			(size 0.3556 1.524)
			(layers "F.Cu" "F.Mask" "F.Paste")
			(net "DRIVE_A_29_INS")
		)
		(pad "19" smd rect
			(at -0.32512 -2.8194)
			(size 0.3556 1.524)
			(layers "F.Cu" "F.Mask" "F.Paste")
			(net "DRIVE_A_30_INS")
		)
		(pad "20" smd rect
			(at -0.97536 -2.8194)
			(size 0.3556 1.524)
			(layers "F.Cu" "F.Mask" "F.Paste")
			(net "DRIVE_A_31_INS")
		)
		(pad "21" smd rect
			(at -1.6256 -2.8194)
			(size 0.3556 1.524)
			(layers "F.Cu" "F.Mask" "F.Paste")
			(net "IO_EXP5_A0")
		)
		(pad "22" smd rect
			(at -2.27584 -2.8194)
			(size 0.3556 1.524)
			(layers "F.Cu" "F.Mask" "F.Paste")
			(net "IO_EXP5_SCL")
		)
		(pad "23" smd rect
			(at -2.92608 -2.8194)
			(size 0.3556 1.524)
			(layers "F.Cu" "F.Mask" "F.Paste")
			(net "IO_EXP5_SDA")
		)
		(pad "24" smd rect
			(at -3.57632 -2.8194)
			(size 0.3556 1.524)
			(layers "F.Cu" "F.Mask" "F.Paste")
			(net "P3V3_STBY_A")
		)
	)
	(footprint ""
		(layer "F.Cu")
		(at 219.89542 -11.017504 90)
		(property "Reference" "C44"
			(at 0 0 90)
			(layer "F.SilkS")
			(hide yes)
			(effects
				(font
					(size 1.27 1.27)
				)
			)
		)
		(property "Value" "SC10U16V5KX-7-GP-U"
			(at -0.0762 -6.1214 90)
			(unlocked yes)
			(layer "F.Fab")
			(hide yes)
			(effects
				(font
					(size 1.016 1.016)
					(thickness 0.1524)
				)
			)
		)
		(property "Device Type" "C805H58"
			(at -0.0762 -8.1534 90)
			(unlocked yes)
			(layer "F.Fab")
			(hide yes)
			(effects
				(font
					(size 1.016 1.016)
					(thickness 0.1524)
				)
			)
		)
		(duplicate_pad_numbers_are_jumpers no)
		(fp_line
			(start 0.635 0)
			(end -0.635 0)
			(stroke
				(width 0.508)
				(type default)
			)
			(layer "F.SilkS")
		)
		(fp_rect
			(start -0.9652 1.778)
			(end 0.9652 -1.778)
			(stroke
				(width 0)
				(type default)
			)
			(fill no)
			(layer "F.CrtYd")
		)
		(fp_poly
			(pts
				(xy -0.9652 -1.778) (xy 0.9652 -1.778) (xy 0.9652 1.778) (xy -0.9652 1.778)
			)
			(stroke
				(width 0)
				(type default)
			)
			(fill no)
			(layer "F.Fab")
		)
		(pad "1" smd rect
			(at 0 -0.9652 90)
			(size 1.397 1.143)
			(layers "F.Cu" "F.Mask" "F.Paste")
			(net "P5V_A_2")
		)
		(pad "2" smd rect
			(at 0 0.9652 90)
			(size 1.397 1.143)
			(layers "F.Cu" "F.Mask" "F.Paste")
			(net "GND")
		)
	)
	(footprint ""
		(layer "F.Cu")
		(at 18.500598 -45.633894)
		(property "Reference" "R699"
			(at 0 0 0)
			(layer "F.SilkS")
			(hide yes)
			(effects
				(font
					(size 1.27 1.27)
				)
			)
		)
		(property "Value" "0R2J-2-GP"
			(at 0.064008 -3.993896 0)
			(unlocked yes)
			(layer "F.Fab")
			(hide yes)
			(effects
				(font
					(size 1.016 1.016)
					(thickness 0.1524)
				)
			)
		)
		(property "Device Type" "R402H16"
			(at 0.064008 -5.517896 0)
			(unlocked yes)
			(layer "F.Fab")
			(hide yes)
			(effects
				(font
					(size 1.016 1.016)
					(thickness 0.1524)
				)
			)
		)
		(duplicate_pad_numbers_are_jumpers no)
		(fp_line
			(start -0.508 -0.9398)
			(end -0.508 0.9398)
			(stroke
				(width 0.1524)
				(type default)
			)
			(layer "F.SilkS")
		)
		(fp_line
			(start 0.508 -0.9398)
			(end -0.508 -0.9398)
			(stroke
				(width 0.1524)
				(type default)
			)
			(layer "F.SilkS")
		)
		(fp_rect
			(start -0.508 0.9398)
			(end 0.508 -0.9398)
			(stroke
				(width 0)
				(type default)
			)
			(fill no)
			(layer "F.CrtYd")
		)
		(fp_rect
			(start -0.508 0.9398)
			(end 0.508 -0.9398)
			(stroke
				(width 0)
				(type default)
			)
			(fill no)
			(layer "F.Fab")
		)
		(pad "1" smd custom
			(at 0 -0.4445)
			(size 0.1397 0.1397)
			(layers "F.Cu" "F.Mask" "F.Paste")
			(net "SW_HDD_G24")
			(options
				(clearance outline)
				(anchor circle)
			)
			(primitives
				(gr_poly
					(pts
						(arc
							(start -0.1778 -0.2794)
							(mid -0.249642 -0.249642)
							(end -0.2794 -0.1778)
						)
						(arc
							(start -0.2794 0.1778)
							(mid -0.249642 0.249642)
							(end -0.1778 0.2794)
						)
						(arc
							(start 0.1778 0.2794)
							(mid 0.249642 0.249642)
							(end 0.2794 0.1778)
						)
						(arc
							(start 0.2794 -0.1778)
							(mid 0.249642 -0.249642)
							(end 0.1778 -0.2794)
						)
					)
					(width 0)
					(fill yes)
				)
			)
		)
		(pad "2" smd custom
			(at 0 0.4445)
			(size 0.1397 0.1397)
			(layers "F.Cu" "F.Mask" "F.Paste")
			(net "SW_HDD_R24")
			(options
				(clearance outline)
				(anchor circle)
			)
			(primitives
				(gr_poly
					(pts
						(arc
							(start -0.1778 -0.2794)
							(mid -0.249642 -0.249642)
							(end -0.2794 -0.1778)
						)
						(arc
							(start -0.2794 0.1778)
							(mid -0.249642 0.249642)
							(end -0.1778 0.2794)
						)
						(arc
							(start 0.1778 0.2794)
							(mid 0.249642 0.249642)
							(end 0.2794 0.1778)
						)
						(arc
							(start 0.2794 -0.1778)
							(mid 0.249642 -0.249642)
							(end 0.1778 -0.2794)
						)
					)
					(width 0)
					(fill yes)
				)
			)
		)
	)
	(footprint ""
		(layer "F.Cu")
		(at 374.5738 -145.8214)
		(property "Reference" "R1085"
			(at 0 0 0)
			(layer "F.SilkS")
			(hide yes)
			(effects
				(font
					(size 1.27 1.27)
				)
			)
		)
		(property "Value" "10KR2F-2-GP"
			(at 0.064008 -3.993896 0)
			(unlocked yes)
			(layer "F.Fab")
			(hide yes)
			(effects
				(font
					(size 1.016 1.016)
					(thickness 0.1524)
				)
			)
		)
		(property "Device Type" "R402H16"
			(at 0.064008 -5.517896 0)
			(unlocked yes)
			(layer "F.Fab")
			(hide yes)
			(effects
				(font
					(size 1.016 1.016)
					(thickness 0.1524)
				)
			)
		)
		(duplicate_pad_numbers_are_jumpers no)
		(fp_line
			(start -0.508 -0.9398)
			(end -0.508 0.9398)
			(stroke
				(width 0.1524)
				(type default)
			)
			(layer "F.SilkS")
		)
		(fp_line
			(start 0.508 -0.9398)
			(end -0.508 -0.9398)
			(stroke
				(width 0.1524)
				(type default)
			)
			(layer "F.SilkS")
		)
		(fp_rect
			(start -0.508 0.9398)
			(end 0.508 -0.9398)
			(stroke
				(width 0)
				(type default)
			)
			(fill no)
			(layer "F.CrtYd")
		)
		(fp_rect
			(start -0.508 0.9398)
			(end 0.508 -0.9398)
			(stroke
				(width 0)
				(type default)
			)
			(fill no)
			(layer "F.Fab")
		)
		(pad "1" smd custom
			(at 0 -0.4445)
			(size 0.1397 0.1397)
			(layers "F.Cu" "F.Mask" "F.Paste")
			(net "P12V_B_COMP")
			(options
				(clearance outline)
				(anchor circle)
			)
			(primitives
				(gr_poly
					(pts
						(arc
							(start -0.1778 -0.2794)
							(mid -0.249642 -0.249642)
							(end -0.2794 -0.1778)
						)
						(arc
							(start -0.2794 0.1778)
							(mid -0.249642 0.249642)
							(end -0.1778 0.2794)
						)
						(arc
							(start 0.1778 0.2794)
							(mid 0.249642 0.249642)
							(end 0.2794 0.1778)
						)
						(arc
							(start 0.2794 -0.1778)
							(mid 0.249642 -0.249642)
							(end 0.1778 -0.2794)
						)
					)
					(width 0)
					(fill yes)
				)
			)
		)
		(pad "2" smd custom
			(at 0 0.4445)
			(size 0.1397 0.1397)
			(layers "F.Cu" "F.Mask" "F.Paste")
			(net "COMP_B_PGOOD")
			(options
				(clearance outline)
				(anchor circle)
			)
			(primitives
				(gr_poly
					(pts
						(arc
							(start -0.1778 -0.2794)
							(mid -0.249642 -0.249642)
							(end -0.2794 -0.1778)
						)
						(arc
							(start -0.2794 0.1778)
							(mid -0.249642 0.249642)
							(end -0.1778 0.2794)
						)
						(arc
							(start 0.1778 0.2794)
							(mid 0.249642 0.249642)
							(end 0.2794 0.1778)
						)
						(arc
							(start 0.2794 -0.1778)
							(mid 0.249642 -0.249642)
							(end 0.1778 -0.2794)
						)
					)
					(width 0)
					(fill yes)
				)
			)
		)
	)
)
